(kicad_pcb
	(version 20240108)
	(generator "pcbnew")
	(generator_version "8.0")
	(general
		(thickness 1.62)
		(legacy_teardrops no)
	)
	(paper "A4")
	(title_block
		(title "Jetson Orin Baseboard")
		(date "2025-03-12")
		(rev "1.3.4")
		(company "Antmicro Ltd")
		(comment 1 "www.antmicro.com")
		(comment 9 "footprints 677-677 of 677")
	)
	(layers
		(0 "F.Cu" signal)
		(1 "In1.Cu" signal)
		(2 "In2.Cu" signal)
		(3 "In3.Cu" signal)
		(4 "In4.Cu" jumper)
		(5 "In5.Cu" signal)
		(6 "In6.Cu" signal)
		(31 "B.Cu" signal)
		(32 "B.Adhes" user "B.Adhesive")
		(33 "F.Adhes" user "F.Adhesive")
		(34 "B.Paste" user)
		(35 "F.Paste" user)
		(36 "B.SilkS" user "B.Silkscreen")
		(37 "F.SilkS" user "F.Silkscreen")
		(38 "B.Mask" user)
		(39 "F.Mask" user)
		(40 "Dwgs.User" user "User.Drawings")
		(41 "Cmts.User" user "User.Comments")
		(42 "Eco1.User" user "User.Eco1")
		(43 "Eco2.User" user "User.Eco2")
		(44 "Edge.Cuts" user)
		(45 "Margin" user)
		(46 "B.CrtYd" user "B.Courtyard")
		(47 "F.CrtYd" user "F.Courtyard")
		(48 "B.Fab" user)
		(49 "F.Fab" user)
	)
	(footprint "antmicro-footprints:Conn_FFC_WE_68715014x22"
		(layer "B.Cu")
		(at 145.29 94.73 -90)
		(property "Reference" "J7"
			(at 0 3.4 90)
			(layer "B.SilkS")
			(effects
				(font
					(size 0.7 0.7)
					(thickness 0.15)
				)
				(justify left bottom mirror)
			)
		)
		(property "Value" "Conn_FFC_WE_68715014522"
			(at 0 -4.499 90)
			(layer "B.Fab")
			(effects
				(font
					(size 0.7 0.7)
					(thickness 0.15)
				)
				(justify left bottom mirror)
			)
		)
		(property "Footprint" "antmicro-footprints:Conn_FFC_WE_68715014x22"
			(at 0 0 -90)
			(layer "F.Fab")
			(hide yes)
			(effects
				(font
					(size 1.27 1.27)
					(thickness 0.15)
				)
			)
		)
		(property "Datasheet" "https://www.we-online.com/components/products/datasheet/68715014522.pdf"
			(at 0 0 -90)
			(layer "F.Fab")
			(hide yes)
			(effects
				(font
					(size 1.27 1.27)
					(thickness 0.15)
				)
			)
		)
		(property "Author" "Antmicro"
			(at 50.56 240.02 0)
			(layer "B.Fab")
			(hide yes)
			(effects
				(font
					(size 1 1)
					(thickness 0.15)
				)
				(justify mirror)
			)
		)
		(property "License" "Apache-2.0"
			(at 50.56 240.02 0)
			(layer "B.Fab")
			(hide yes)
			(effects
				(font
					(size 1 1)
					(thickness 0.15)
				)
				(justify mirror)
			)
		)
		(property "MPN" "68715014522"
			(at 50.56 240.02 0)
			(layer "B.Fab")
			(hide yes)
			(effects
				(font
					(size 1 1)
					(thickness 0.15)
				)
				(justify mirror)
			)
		)
		(property "Manufacturer" "Würth Elektronik"
			(at 50.56 240.02 0)
			(layer "B.Fab")
			(hide yes)
			(effects
				(font
					(size 1 1)
					(thickness 0.15)
				)
				(justify mirror)
			)
		)
		(sheetname "CSI")
		(sheetfile "csi.kicad_sch")
		(attr smd)
		(fp_line
			(start -12.5 2.976)
			(end -12.5 2.15)
			(stroke
				(width 0.15)
				(type solid)
			)
			(layer "B.SilkS")
		)
		(fp_line
			(start 12.499 2.976)
			(end -12.5 2.976)
			(stroke
				(width 0.15)
				(type solid)
			)
			(layer "B.SilkS")
		)
		(fp_line
			(start 12.499 2.976)
			(end 12.499 2.15)
			(stroke
				(width 0.15)
				(type solid)
			)
			(layer "B.SilkS")
		)
		(fp_line
			(start -15.85 2.15)
			(end -15.85 -2.7)
			(stroke
				(width 0.15)
				(type solid)
			)
			(layer "B.SilkS")
		)
		(fp_line
			(start -12.5 2.15)
			(end -15.85 2.15)
			(stroke
				(width 0.15)
				(type solid)
			)
			(layer "B.SilkS")
		)
		(fp_line
			(start 12.499 2.15)
			(end 15.85 2.15)
			(stroke
				(width 0.15)
				(type solid)
			)
			(layer "B.SilkS")
		)
		(fp_line
			(start 15.85 2.15)
			(end 15.85 -2.7)
			(stroke
				(width 0.15)
				(type solid)
			)
			(layer "B.SilkS")
		)
		(fp_line
			(start -15.85 -2.7)
			(end 15.85 -2.7)
			(stroke
				(width 0.15)
				(type solid)
			)
			(layer "B.SilkS")
		)
		(fp_circle
			(center -12.9 2.9)
			(end -12.85 2.85)
			(stroke
				(width 0.15)
				(type solid)
			)
			(fill solid)
			(layer "B.SilkS")
		)
		(fp_rect
			(start -16.2 3.25)
			(end 16.2 -3.55)
			(stroke
				(width 0.05)
				(type solid)
			)
			(fill none)
			(layer "B.CrtYd")
		)
		(fp_text user "Author: Antmicro"
			(at -16.2 -6.499 90)
			(layer "B.Fab")
			(hide yes)
			(effects
				(font
					(size 0.7 0.7)
					(thickness 0.15)
				)
				(justify left bottom mirror)
			)
		)
		(fp_text user "License: Apache-2.0"
			(at -16.2 -7.7 90)
			(layer "B.Fab")
			(hide yes)
			(effects
				(font
					(size 0.7 0.7)
					(thickness 0.15)
				)
				(justify left bottom mirror)
			)
		)
		(fp_text user "${REFERENCE}"
			(at -16.2 -8.9 90)
			(layer "B.Fab")
			(hide yes)
			(effects
				(font
					(size 0.7 0.7)
					(thickness 0.15)
				)
				(justify left bottom mirror)
			)
		)
		(pad "1" smd roundrect
			(at -12.25 2.15 270)
			(size 0.3 1.2)
			(layers "B.Cu" "B.Paste" "B.Mask")
			(roundrect_rratio 0.25)
			(net 204 "/CSI/CSI1_0_D1_N")
			(pintype "passive")
		)
		(pad "2" smd roundrect
			(at -11.75 2.15 270)
			(size 0.3 1.2)
			(layers "B.Cu" "B.Paste" "B.Mask")
			(roundrect_rratio 0.25)
			(net 205 "/CSI/CSI1_0_D1_P")
			(pintype "passive")
		)
		(pad "3" smd roundrect
			(at -11.25 2.15 270)
			(size 0.3 1.2)
			(layers "B.Cu" "B.Paste" "B.Mask")
			(roundrect_rratio 0.25)
			(net 206 "/CSI/CSI1_0_D0_N")
			(pintype "passive")
		)
		(pad "4" smd roundrect
			(at -10.75 2.15 270)
			(size 0.3 1.2)
			(layers "B.Cu" "B.Paste" "B.Mask")
			(roundrect_rratio 0.25)
			(net 207 "/CSI/CSI1_0_D0_P")
			(pintype "passive")
		)
		(pad "5" smd roundrect
			(at -10.25 2.15 270)
			(size 0.3 1.2)
			(layers "B.Cu" "B.Paste" "B.Mask")
			(roundrect_rratio 0.25)
			(net 11 "CSI0_D1_N")
			(pintype "passive")
		)
		(pad "6" smd roundrect
			(at -9.75 2.15 270)
			(size 0.3 1.2)
			(layers "B.Cu" "B.Paste" "B.Mask")
			(roundrect_rratio 0.25)
			(net 13 "CSI0_D1_P")
			(pintype "passive")
		)
		(pad "7" smd roundrect
			(at -9.25 2.15 270)
			(size 0.3 1.2)
			(layers "B.Cu" "B.Paste" "B.Mask")
			(roundrect_rratio 0.25)
			(net 3 "CSI0_D0_N")
			(pintype "passive")
		)
		(pad "8" smd roundrect
			(at -8.75 2.15 270)
			(size 0.3 1.2)
			(layers "B.Cu" "B.Paste" "B.Mask")
			(roundrect_rratio 0.25)
			(net 5 "CSI0_D0_P")
			(pintype "passive")
		)
		(pad "9" smd roundrect
			(at -8.25 2.15 270)
			(size 0.3 1.2)
			(layers "B.Cu" "B.Paste" "B.Mask")
			(roundrect_rratio 0.25)
			(net 1 "GND")
			(pintype "passive")
		)
		(pad "10" smd roundrect
			(at -7.75 2.15 270)
			(size 0.3 1.2)
			(layers "B.Cu" "B.Paste" "B.Mask")
			(roundrect_rratio 0.25)
			(net 7 "CSI0_CLK_N")
			(pintype "passive")
		)
		(pad "11" smd roundrect
			(at -7.25 2.15 270)
			(size 0.3 1.2)
			(layers "B.Cu" "B.Paste" "B.Mask")
			(roundrect_rratio 0.25)
			(net 9 "CSI0_CLK_P")
			(pintype "passive")
		)
		(pad "12" smd roundrect
			(at -6.75 2.15 270)
			(size 0.3 1.2)
			(layers "B.Cu" "B.Paste" "B.Mask")
			(roundrect_rratio 0.25)
			(net 1 "GND")
			(pintype "passive")
		)
		(pad "13" smd roundrect
			(at -6.25 2.15 270)
			(size 0.3 1.2)
			(layers "B.Cu" "B.Paste" "B.Mask")
			(roundrect_rratio 0.25)
			(net 326 "unconnected-(J7-Pad13)")
			(pintype "passive+no_connect")
		)
		(pad "14" smd roundrect
			(at -5.75 2.15 270)
			(size 0.3 1.2)
			(layers "B.Cu" "B.Paste" "B.Mask")
			(roundrect_rratio 0.25)
			(net 339 "unconnected-(J7-Pad14)")
			(pintype "passive+no_connect")
		)
		(pad "15" smd roundrect
			(at -5.25 2.15 270)
			(size 0.3 1.2)
			(layers "B.Cu" "B.Paste" "B.Mask")
			(roundrect_rratio 0.25)
			(net 1 "GND")
			(pintype "passive")
		)
		(pad "16" smd roundrect
			(at -4.75 2.15 270)
			(size 0.3 1.2)
			(layers "B.Cu" "B.Paste" "B.Mask")
			(roundrect_rratio 0.25)
			(net 340 "unconnected-(J7-Pad16)")
			(pintype "passive+no_connect")
		)
		(pad "17" smd roundrect
			(at -4.25 2.15 270)
			(size 0.3 1.2)
			(layers "B.Cu" "B.Paste" "B.Mask")
			(roundrect_rratio 0.25)
			(net 626 "unconnected-(J7-Pad17)")
			(pintype "passive+no_connect")
		)
		(pad "18" smd roundrect
			(at -3.75 2.15 270)
			(size 0.3 1.2)
			(layers "B.Cu" "B.Paste" "B.Mask")
			(roundrect_rratio 0.25)
			(net 1 "GND")
			(pintype "passive")
		)
		(pad "19" smd roundrect
			(at -3.25 2.15 270)
			(size 0.3 1.2)
			(layers "B.Cu" "B.Paste" "B.Mask")
			(roundrect_rratio 0.25)
			(net 212 "/CSI/CSI3_0_D1_N")
			(pintype "passive")
		)
		(pad "20" smd roundrect
			(at -2.75 2.15 270)
			(size 0.3 1.2)
			(layers "B.Cu" "B.Paste" "B.Mask")
			(roundrect_rratio 0.25)
			(net 213 "/CSI/CSI3_0_D1_P")
			(pintype "passive")
		)
		(pad "21" smd roundrect
			(at -2.25 2.15 270)
			(size 0.3 1.2)
			(layers "B.Cu" "B.Paste" "B.Mask")
			(roundrect_rratio 0.25)
			(net 214 "/CSI/CSI3_0_D0_N")
			(pintype "passive")
		)
		(pad "22" smd roundrect
			(at -1.75 2.15 270)
			(size 0.3 1.2)
			(layers "B.Cu" "B.Paste" "B.Mask")
			(roundrect_rratio 0.25)
			(net 215 "/CSI/CSI3_0_D0_P")
			(pintype "passive")
		)
		(pad "23" smd roundrect
			(at -1.25 2.15 270)
			(size 0.3 1.2)
			(layers "B.Cu" "B.Paste" "B.Mask")
			(roundrect_rratio 0.25)
			(net 23 "CSI2_D1_N")
			(pintype "passive")
		)
		(pad "24" smd roundrect
			(at -0.75 2.15 270)
			(size 0.3 1.2)
			(layers "B.Cu" "B.Paste" "B.Mask")
			(roundrect_rratio 0.25)
			(net 25 "CSI2_D1_P")
			(pintype "passive")
		)
		(pad "25" smd roundrect
			(at -0.25 2.15 270)
			(size 0.3 1.2)
			(layers "B.Cu" "B.Paste" "B.Mask")
			(roundrect_rratio 0.25)
			(net 15 "CSI2_D0_N")
			(pintype "passive")
		)
		(pad "26" smd roundrect
			(at 0.248 2.15 270)
			(size 0.3 1.2)
			(layers "B.Cu" "B.Paste" "B.Mask")
			(roundrect_rratio 0.25)
			(net 17 "CSI2_D0_P")
			(pintype "passive")
		)
		(pad "27" smd roundrect
			(at 0.748 2.15 270)
			(size 0.3 1.2)
			(layers "B.Cu" "B.Paste" "B.Mask")
			(roundrect_rratio 0.25)
			(net 1 "GND")
			(pintype "passive")
		)
		(pad "28" smd roundrect
			(at 1.249 2.15 270)
			(size 0.3 1.2)
			(layers "B.Cu" "B.Paste" "B.Mask")
			(roundrect_rratio 0.25)
			(net 19 "CSI2_CLK_N")
			(pintype "passive")
		)
		(pad "29" smd roundrect
			(at 1.749 2.15 270)
			(size 0.3 1.2)
			(layers "B.Cu" "B.Paste" "B.Mask")
			(roundrect_rratio 0.25)
			(net 21 "CSI2_CLK_P")
			(pintype "passive")
		)
		(pad "30" smd roundrect
			(at 2.249 2.15 270)
			(size 0.3 1.2)
			(layers "B.Cu" "B.Paste" "B.Mask")
			(roundrect_rratio 0.25)
			(net 1 "GND")
			(pintype "passive")
		)
		(pad "31" smd roundrect
			(at 2.749 2.15 270)
			(size 0.3 1.2)
			(layers "B.Cu" "B.Paste" "B.Mask")
			(roundrect_rratio 0.25)
			(net 627 "unconnected-(J7-Pad31)")
			(pintype "passive+no_connect")
		)
		(pad "32" smd roundrect
			(at 3.249 2.15 270)
			(size 0.3 1.2)
			(layers "B.Cu" "B.Paste" "B.Mask")
			(roundrect_rratio 0.25)
			(net 360 "/CSI/VSYNC_CAM0_3V3")
			(pintype "passive")
		)
		(pad "33" smd roundrect
			(at 3.749 2.15 270)
			(size 0.3 1.2)
			(layers "B.Cu" "B.Paste" "B.Mask")
			(roundrect_rratio 0.25)
			(net 361 "unconnected-(J7-Pad33)")
			(pintype "passive+no_connect")
		)
		(pad "34" smd roundrect
			(at 4.248 2.15 270)
			(size 0.3 1.2)
			(layers "B.Cu" "B.Paste" "B.Mask")
			(roundrect_rratio 0.25)
			(net 371 "/CSI/VSYNC_CAM1_3V3")
			(pintype "passive")
		)
		(pad "35" smd roundrect
			(at 4.748 2.15 270)
			(size 0.3 1.2)
			(layers "B.Cu" "B.Paste" "B.Mask")
			(roundrect_rratio 0.25)
			(net 372 "unconnected-(J7-Pad35)")
			(pintype "passive+no_connect")
		)
		(pad "36" smd roundrect
			(at 5.248 2.15 270)
			(size 0.3 1.2)
			(layers "B.Cu" "B.Paste" "B.Mask")
			(roundrect_rratio 0.25)
			(net 373 "unconnected-(J7-Pad36)")
			(pintype "passive+no_connect")
		)
		(pad "37" smd roundrect
			(at 5.749 2.15 270)
			(size 0.3 1.2)
			(layers "B.Cu" "B.Paste" "B.Mask")
			(roundrect_rratio 0.25)
			(net 374 "unconnected-(J7-Pad37)")
			(pintype "passive+no_connect")
		)
		(pad "38" smd roundrect
			(at 6.249 2.15 270)
			(size 0.3 1.2)
			(layers "B.Cu" "B.Paste" "B.Mask")
			(roundrect_rratio 0.25)
			(net 376 "unconnected-(J7-Pad38)")
			(pintype "passive+no_connect")
		)
		(pad "39" smd roundrect
			(at 6.749 2.15 270)
			(size 0.3 1.2)
			(layers "B.Cu" "B.Paste" "B.Mask")
			(roundrect_rratio 0.25)
			(net 554 "Net-(R50-R1.2)")
			(pintype "passive")
		)
		(pad "40" smd roundrect
			(at 7.249 2.15 270)
			(size 0.3 1.2)
			(layers "B.Cu" "B.Paste" "B.Mask")
			(roundrect_rratio 0.25)
			(net 559 "Net-(R50-R2.2)")
			(pintype "passive")
		)
		(pad "41" smd roundrect
			(at 7.749 2.15 270)
			(size 0.3 1.2)
			(layers "B.Cu" "B.Paste" "B.Mask")
			(roundrect_rratio 0.25)
			(net 560 "Net-(R50-R3.2)")
			(pintype "passive")
		)
		(pad "42" smd roundrect
			(at 8.249 2.15 270)
			(size 0.3 1.2)
			(layers "B.Cu" "B.Paste" "B.Mask")
			(roundrect_rratio 0.25)
			(net 563 "Net-(R50-R4.2)")
			(pintype "passive")
		)
		(pad "43" smd roundrect
			(at 8.749 2.15 270)
			(size 0.3 1.2)
			(layers "B.Cu" "B.Paste" "B.Mask")
			(roundrect_rratio 0.25)
			(net 377 "unconnected-(J7-Pad43)")
			(pintype "passive+no_connect")
		)
		(pad "44" smd roundrect
			(at 9.249 2.15 270)
			(size 0.3 1.2)
			(layers "B.Cu" "B.Paste" "B.Mask")
			(roundrect_rratio 0.25)
			(net 378 "unconnected-(J7-Pad44)")
			(pintype "passive+no_connect")
		)
		(pad "45" smd roundrect
			(at 9.749 2.15 270)
			(size 0.3 1.2)
			(layers "B.Cu" "B.Paste" "B.Mask")
			(roundrect_rratio 0.25)
			(net 379 "unconnected-(J7-Pad45)")
			(pintype "passive+no_connect")
		)
		(pad "46" smd roundrect
			(at 10.249 2.15 270)
			(size 0.3 1.2)
			(layers "B.Cu" "B.Paste" "B.Mask")
			(roundrect_rratio 0.25)
			(net 380 "unconnected-(J7-Pad46)")
			(pintype "passive+no_connect")
		)
		(pad "47" smd roundrect
			(at 10.749 2.15 270)
			(size 0.3 1.2)
			(layers "B.Cu" "B.Paste" "B.Mask")
			(roundrect_rratio 0.25)
			(net 108 "/CSI/CSIA_3V3")
			(pintype "passive")
		)
		(pad "48" smd roundrect
			(at 11.249 2.15 270)
			(size 0.3 1.2)
			(layers "B.Cu" "B.Paste" "B.Mask")
			(roundrect_rratio 0.25)
			(net 108 "/CSI/CSIA_3V3")
			(pintype "passive")
		)
		(pad "49" smd roundrect
			(at 11.749 2.15 270)
			(size 0.3 1.2)
			(layers "B.Cu" "B.Paste" "B.Mask")
			(roundrect_rratio 0.25)
			(net 109 "/CSI/CSIA_5V")
			(pintype "passive")
		)
		(pad "50" smd roundrect
			(at 12.249 2.15 270)
			(size 0.3 1.2)
			(layers "B.Cu" "B.Paste" "B.Mask")
			(roundrect_rratio 0.25)
			(net 109 "/CSI/CSIA_5V")
			(pintype "passive")
		)
		(pad "MP1" smd roundrect
			(at -14.198 0.3 270)
			(size 2.7 3)
			(layers "B.Cu" "B.Paste" "B.Mask")
			(roundrect_rratio 0.05)
			(net 1 "GND")
			(pinfunction "MP")
			(pintype "passive")
		)
		(pad "MP2" smd roundrect
			(at 14.198 0.3 270)
			(size 2.7 3)
			(layers "B.Cu" "B.Paste" "B.Mask")
			(roundrect_rratio 0.05)
			(net 1 "GND")
			(pinfunction "MP")
			(pintype "passive")
		)
	)
)
